(kicad_pcb
	(version 20241229)
	(generator "pcbnew")
	(generator_version "9.0")
	(general
		(thickness 1.6296)
		(legacy_teardrops no)
	)
	(paper "A3")
	(title_block
		(title "Thunderbolt to 10GbE adapter")
		(date "2026-04-21")
		(rev "1.1.0")
		(company "Antmicro Ltd")
		(comment 1 "www.antmicro.com")
		(comment 9 "footprints 42-45 of 703")
	)
	(layers
		(0 "F.Cu" signal)
		(4 "In1.Cu" signal)
		(6 "In2.Cu" signal)
		(8 "In3.Cu" signal)
		(10 "In4.Cu" signal)
		(12 "In5.Cu" signal)
		(14 "In6.Cu" signal)
		(2 "B.Cu" signal)
		(9 "F.Adhes" user "F.Adhesive")
		(11 "B.Adhes" user "B.Adhesive")
		(13 "F.Paste" user)
		(15 "B.Paste" user)
		(5 "F.SilkS" user "F.Silkscreen")
		(7 "B.SilkS" user "B.Silkscreen")
		(1 "F.Mask" user)
		(3 "B.Mask" user)
		(17 "Dwgs.User" user "User.Drawings")
		(19 "Cmts.User" user "User.Comments")
		(21 "Eco1.User" user "User.Eco1")
		(23 "Eco2.User" user "User.Eco2")
		(25 "Edge.Cuts" user)
		(27 "Margin" user)
		(31 "F.CrtYd" user "F.Courtyard")
		(29 "B.CrtYd" user "B.Courtyard")
		(35 "F.Fab" user)
		(33 "B.Fab" user)
	)
	(footprint "antmicro-footprints:R_0402_1005Metric"
		(layer "F.Cu")
		(at 164 78.4 180)
		(descr "Resistor SMD 0402")
		(tags "resistor SMD 0402")
		(property "Reference" "R208"
			(at 1 -6.4 180)
			(layer "F.SilkS")
			(effects
				(font
					(size 0.7 0.7)
					(thickness 0.15)
				)
				(justify left bottom)
			)
		)
		(property "Value" "R_0R_0402"
			(at -1.011843 1.772047 180)
			(layer "F.Fab")
			(effects
				(font
					(size 0.7 0.7)
					(thickness 0.15)
				)
				(justify left bottom)
			)
		)
		(property "Datasheet" "https://industrial.panasonic.com/cdbs/www-data/pdf/RDA0000/AOA0000C301.pdf"
			(at 0 0 180)
			(layer "F.Fab")
			(hide yes)
			(effects
				(font
					(size 1.27 1.27)
					(thickness 0.15)
				)
			)
		)
		(property "Description" "SMD Chip Resistor, Jumper, 0 ohm, 100 mW, 0402 [1005 Metric], Thick Film, General Purpose"
			(at 0 0 180)
			(layer "F.Fab")
			(hide yes)
			(effects
				(font
					(size 1.27 1.27)
					(thickness 0.15)
				)
			)
		)
		(property "MPN" "ERJ2GE0R00X"
			(at 0 0 180)
			(unlocked yes)
			(layer "F.Fab")
			(hide yes)
			(effects
				(font
					(size 1 1)
					(thickness 0.15)
				)
			)
		)
		(property "Manufacturer" "Panasonic"
			(at 0 0 180)
			(unlocked yes)
			(layer "F.Fab")
			(hide yes)
			(effects
				(font
					(size 1 1)
					(thickness 0.15)
				)
			)
		)
		(property "License" "Apache-2.0"
			(at 0 0 180)
			(unlocked yes)
			(layer "F.Fab")
			(hide yes)
			(effects
				(font
					(size 1 1)
					(thickness 0.15)
				)
			)
		)
		(property "Author" "Antmicro"
			(at 0 0 180)
			(unlocked yes)
			(layer "F.Fab")
			(hide yes)
			(effects
				(font
					(size 1 1)
					(thickness 0.15)
				)
			)
		)
		(property "Val" "0R"
			(at 0 0 180)
			(unlocked yes)
			(layer "F.Fab")
			(hide yes)
			(effects
				(font
					(size 1 1)
					(thickness 0.15)
				)
			)
		)
		(property "Tolerance" "~"
			(at 0 0 180)
			(unlocked yes)
			(layer "F.Fab")
			(hide yes)
			(effects
				(font
					(size 1 1)
					(thickness 0.15)
				)
			)
		)
		(property "Current" "1A"
			(at 0 0 180)
			(unlocked yes)
			(layer "F.Fab")
			(hide yes)
			(effects
				(font
					(size 1 1)
					(thickness 0.15)
				)
			)
		)
		(sheetname "/X710-AT2 10GbE/")
		(sheetfile "x710-at2-10gbe.kicad_sch")
		(attr smd)
		(fp_rect
			(start -0.925 -0.47)
			(end 0.925 0.47)
			(stroke
				(width 0.05)
				(type default)
			)
			(fill no)
			(layer "F.CrtYd")
		)
		(fp_rect
			(start -0.5 -0.25)
			(end 0.5 0.25)
			(stroke
				(width 0.15)
				(type solid)
			)
			(fill no)
			(layer "F.Fab")
		)
		(fp_text user "${REFERENCE}"
			(at -0.95 3.168 180)
			(layer "F.Fab")
			(effects
				(font
					(size 0.7 0.7)
					(thickness 0.15)
				)
				(justify left bottom)
			)
		)
		(fp_text user "License: Apache-2.0"
			(at -0.95 5.169 180)
			(layer "F.Fab")
			(effects
				(font
					(size 0.7 0.7)
					(thickness 0.15)
				)
				(justify left bottom)
			)
		)
		(fp_text user "Author: Antmicro"
			(at -0.95 4.169 180)
			(layer "F.Fab")
			(effects
				(font
					(size 0.7 0.7)
					(thickness 0.15)
				)
				(justify left bottom)
			)
		)
		(pad "1" smd roundrect
			(at -0.48 0 180)
			(size 0.59 0.64)
			(layers "F.Cu" "F.Mask" "F.Paste")
			(roundrect_rratio 0.25)
			(net 23 "GND")
			(pintype "passive")
		)
		(pad "2" smd roundrect
			(at 0.48 0 180)
			(size 0.59 0.64)
			(layers "F.Cu" "F.Mask" "F.Paste")
			(roundrect_rratio 0.25)
			(net 131 "/X710-AT2 10GbE/TPIN_5")
			(pintype "passive")
		)
	)
	(footprint "antmicro-footprints:R_0402_1005Metric"
		(layer "F.Cu")
		(at 117 71.9 180)
		(descr "Resistor SMD 0402")
		(tags "resistor SMD 0402")
		(property "Reference" "R216"
			(at -3.6 10.5 180)
			(layer "F.SilkS")
			(effects
				(font
					(size 0.7 0.7)
					(thickness 0.15)
				)
				(justify left bottom)
			)
		)
		(property "Value" "R_6k04_0.1%_0402"
			(at -1.011843 1.772047 180)
			(layer "F.Fab")
			(effects
				(font
					(size 0.7 0.7)
					(thickness 0.15)
				)
				(justify left bottom)
			)
		)
		(property "Datasheet" "https://www.vishay.com/docs/28758/tnpw_e3.pdf"
			(at 0 0 180)
			(layer "F.Fab")
			(hide yes)
			(effects
				(font
					(size 1.27 1.27)
					(thickness 0.15)
				)
			)
		)
		(property "Description" "SMD Chip Resistor, 6.49 kohm, ± 1%, 62.5 mW, 0402 [1005 Metric], Thick Film, General Purpose"
			(at 0 0 180)
			(layer "F.Fab")
			(hide yes)
			(effects
				(font
					(size 1.27 1.27)
					(thickness 0.15)
				)
			)
		)
		(property "MPN" "TNPW04026K04BEED"
			(at 0 0 180)
			(unlocked yes)
			(layer "F.Fab")
			(hide yes)
			(effects
				(font
					(size 1 1)
					(thickness 0.15)
				)
			)
		)
		(property "Manufacturer" "Vishay"
			(at 0 0 180)
			(unlocked yes)
			(layer "F.Fab")
			(hide yes)
			(effects
				(font
					(size 1 1)
					(thickness 0.15)
				)
			)
		)
		(property "License" "Apache-2.0"
			(at 0 0 180)
			(unlocked yes)
			(layer "F.Fab")
			(hide yes)
			(effects
				(font
					(size 1 1)
					(thickness 0.15)
				)
			)
		)
		(property "Author" "Antmicro"
			(at 0 0 180)
			(unlocked yes)
			(layer "F.Fab")
			(hide yes)
			(effects
				(font
					(size 1 1)
					(thickness 0.15)
				)
			)
		)
		(property "Val" "6k04"
			(at 0 0 180)
			(unlocked yes)
			(layer "F.Fab")
			(hide yes)
			(effects
				(font
					(size 1 1)
					(thickness 0.15)
				)
			)
		)
		(property "Tolerance" "0.1%"
			(at 0 0 180)
			(unlocked yes)
			(layer "F.Fab")
			(hide yes)
			(effects
				(font
					(size 1 1)
					(thickness 0.15)
				)
			)
		)
		(sheetname "/Fan controller/")
		(sheetfile "fan-controller.kicad_sch")
		(attr smd)
		(fp_rect
			(start -0.925 -0.47)
			(end 0.925 0.47)
			(stroke
				(width 0.05)
				(type default)
			)
			(fill no)
			(layer "F.CrtYd")
		)
		(fp_rect
			(start -0.5 -0.25)
			(end 0.5 0.25)
			(stroke
				(width 0.15)
				(type solid)
			)
			(fill no)
			(layer "F.Fab")
		)
		(fp_text user "${REFERENCE}"
			(at -0.95 3.168 180)
			(layer "F.Fab")
			(effects
				(font
					(size 0.7 0.7)
					(thickness 0.15)
				)
				(justify left bottom)
			)
		)
		(fp_text user "License: Apache-2.0"
			(at -0.95 5.169 180)
			(layer "F.Fab")
			(effects
				(font
					(size 0.7 0.7)
					(thickness 0.15)
				)
				(justify left bottom)
			)
		)
		(fp_text user "Author: Antmicro"
			(at -0.95 4.169 180)
			(layer "F.Fab")
			(effects
				(font
					(size 0.7 0.7)
					(thickness 0.15)
				)
				(justify left bottom)
			)
		)
		(pad "1" smd roundrect
			(at -0.48 0 180)
			(size 0.59 0.64)
			(layers "F.Cu" "F.Mask" "F.Paste")
			(roundrect_rratio 0.25)
			(net 446 "Net-(R216-Pad1)")
			(pintype "passive")
		)
		(pad "2" smd roundrect
			(at 0.48 0 180)
			(size 0.59 0.64)
			(layers "F.Cu" "F.Mask" "F.Paste")
			(roundrect_rratio 0.25)
			(net 40 "+5V")
			(pintype "passive")
		)
	)
	(footprint "antmicro-footprints:C_0402_1005Metric"
		(layer "F.Cu")
		(at 116.4 106.09 180)
		(descr "Capacitor SMD 0402")
		(tags "capacitor SMD 0402")
		(property "Reference" "C17"
			(at 0 8.1 180)
			(layer "F.SilkS")
			(effects
				(font
					(size 0.7 0.7)
					(thickness 0.15)
				)
			)
		)
		(property "Value" "C_33p_0402"
			(at -1.022927 2.155213 180)
			(layer "F.Fab")
			(effects
				(font
					(size 0.7 0.7)
					(thickness 0.15)
				)
				(justify left bottom)
			)
		)
		(property "Datasheet" "https://spicat.kyocera-avx.com/product/mlcc/chartview/04025A330FAT2A/"
			(at 0 0 180)
			(layer "F.Fab")
			(hide yes)
			(effects
				(font
					(size 1.27 1.27)
					(thickness 0.15)
				)
			)
		)
		(property "Description" "SMD Multilayer Ceramic Capacitor, 33 pF, 50 V, 0402 [1005 Metric], ± 5%, C0G / NP0, MC"
			(at 0 0 180)
			(layer "F.Fab")
			(hide yes)
			(effects
				(font
					(size 1.27 1.27)
					(thickness 0.15)
				)
			)
		)
		(property "MPN" "04025A330FAT2A"
			(at 0 0 180)
			(unlocked yes)
			(layer "F.Fab")
			(hide yes)
			(effects
				(font
					(size 1 1)
					(thickness 0.15)
				)
			)
		)
		(property "Manufacturer" "KYOCERA AVX"
			(at 0 0 180)
			(unlocked yes)
			(layer "F.Fab")
			(hide yes)
			(effects
				(font
					(size 1 1)
					(thickness 0.15)
				)
			)
		)
		(property "License" "Apache-2.0"
			(at 0 0 180)
			(unlocked yes)
			(layer "F.Fab")
			(hide yes)
			(effects
				(font
					(size 1 1)
					(thickness 0.15)
				)
			)
		)
		(property "Val" "33p"
			(at 0 0 180)
			(unlocked yes)
			(layer "F.Fab")
			(hide yes)
			(effects
				(font
					(size 1 1)
					(thickness 0.15)
				)
			)
		)
		(property "Voltage" ""
			(at 0 0 180)
			(unlocked yes)
			(layer "F.Fab")
			(hide yes)
			(effects
				(font
					(size 1 1)
					(thickness 0.15)
				)
			)
		)
		(property "Dielectric" ""
			(at 0 0 180)
			(unlocked yes)
			(layer "F.Fab")
			(hide yes)
			(effects
				(font
					(size 1 1)
					(thickness 0.15)
				)
			)
		)
		(property "Author" "Antmicro"
			(at 0 0 180)
			(unlocked yes)
			(layer "F.Fab")
			(hide yes)
			(effects
				(font
					(size 1 1)
					(thickness 0.15)
				)
			)
		)
		(sheetname "/PD and TB DC-DC/")
		(sheetfile "PD_and_TB_DC_DC.kicad_sch")
		(attr smd)
		(fp_rect
			(start -0.925 -0.47)
			(end 0.925 0.47)
			(stroke
				(width 0.05)
				(type default)
			)
			(fill no)
			(layer "F.CrtYd")
		)
		(fp_line
			(start 0.504 0.248)
			(end -0.494 0.248)
			(stroke
				(width 0.15)
				(type solid)
			)
			(layer "F.Fab")
		)
		(fp_line
			(start 0.504 -0.25)
			(end 0.504 0.248)
			(stroke
				(width 0.15)
				(type solid)
			)
			(layer "F.Fab")
		)
		(fp_line
			(start -0.494 0.248)
			(end -0.494 -0.25)
			(stroke
				(width 0.15)
				(type solid)
			)
			(layer "F.Fab")
		)
		(fp_line
			(start -0.494 -0.25)
			(end 0.504 -0.25)
			(stroke
				(width 0.15)
				(type solid)
			)
			(layer "F.Fab")
		)
		(fp_text user "Author: Antmicro"
			(at -0.939 3.399 180)
			(layer "F.Fab")
			(effects
				(font
					(size 0.7 0.7)
					(thickness 0.15)
				)
				(justify left bottom)
			)
		)
		(fp_text user "${REFERENCE}"
			(at -0.939 4.599 180)
			(layer "F.Fab")
			(effects
				(font
					(size 0.7 0.7)
					(thickness 0.15)
				)
				(justify left bottom)
			)
		)
		(fp_text user "License: Apache-2.0"
			(at -0.939 5.799 180)
			(layer "F.Fab")
			(effects
				(font
					(size 0.7 0.7)
					(thickness 0.15)
				)
				(justify left bottom)
			)
		)
		(pad "1" smd roundrect
			(at -0.48 0 180)
			(size 0.59 0.64)
			(layers "F.Cu" "F.Mask" "F.Paste")
			(roundrect_rratio 0.25)
			(net 166 "Net-(U2-FB)")
			(pintype "passive")
		)
		(pad "2" smd roundrect
			(at 0.48 0 180)
			(size 0.59 0.64)
			(layers "F.Cu" "F.Mask" "F.Paste")
			(roundrect_rratio 0.25)
			(net 399 "Net-(D4-A)")
			(pintype "passive")
		)
	)
	(footprint "antmicro-footprints:R_0402_1005Metric"
		(layer "F.Cu")
		(at 134 84.2 90)
		(descr "Resistor SMD 0402")
		(tags "resistor SMD 0402")
		(property "Reference" "R138"
			(at -1.2 -4.2 90)
			(layer "F.SilkS")
			(effects
				(font
					(size 0.7 0.7)
					(thickness 0.15)
				)
				(justify left bottom)
			)
		)
		(property "Value" "R_0R_0402"
			(at -1.011843 1.772047 90)
			(layer "F.Fab")
			(effects
				(font
					(size 0.7 0.7)
					(thickness 0.15)
				)
				(justify left bottom)
			)
		)
		(property "Datasheet" "https://industrial.panasonic.com/cdbs/www-data/pdf/RDA0000/AOA0000C301.pdf"
			(at 0 0 90)
			(layer "F.Fab")
			(hide yes)
			(effects
				(font
					(size 1.27 1.27)
					(thickness 0.15)
				)
			)
		)
		(property "Description" "SMD Chip Resistor, Jumper, 0 ohm, 100 mW, 0402 [1005 Metric], Thick Film, General Purpose"
			(at 0 0 90)
			(layer "F.Fab")
			(hide yes)
			(effects
				(font
					(size 1.27 1.27)
					(thickness 0.15)
				)
			)
		)
		(property "MPN" "ERJ2GE0R00X"
			(at 0 0 90)
			(unlocked yes)
			(layer "F.Fab")
			(hide yes)
			(effects
				(font
					(size 1 1)
					(thickness 0.15)
				)
			)
		)
		(property "Manufacturer" "Panasonic"
			(at 0 0 90)
			(unlocked yes)
			(layer "F.Fab")
			(hide yes)
			(effects
				(font
					(size 1 1)
					(thickness 0.15)
				)
			)
		)
		(property "License" "Apache-2.0"
			(at 0 0 90)
			(unlocked yes)
			(layer "F.Fab")
			(hide yes)
			(effects
				(font
					(size 1 1)
					(thickness 0.15)
				)
			)
		)
		(property "Author" "Antmicro"
			(at 0 0 90)
			(unlocked yes)
			(layer "F.Fab")
			(hide yes)
			(effects
				(font
					(size 1 1)
					(thickness 0.15)
				)
			)
		)
		(property "Val" "0R"
			(at 0 0 90)
			(unlocked yes)
			(layer "F.Fab")
			(hide yes)
			(effects
				(font
					(size 1 1)
					(thickness 0.15)
				)
			)
		)
		(property "Tolerance" "~"
			(at 0 0 90)
			(unlocked yes)
			(layer "F.Fab")
			(hide yes)
			(effects
				(font
					(size 1 1)
					(thickness 0.15)
				)
			)
		)
		(property "Current" "1A"
			(at 0 0 90)
			(unlocked yes)
			(layer "F.Fab")
			(hide yes)
			(effects
				(font
					(size 1 1)
					(thickness 0.15)
				)
			)
		)
		(sheetname "/X710-AT2 Misc/")
		(sheetfile "x710-at2-mics.kicad_sch")
		(attr smd dnp)
		(fp_rect
			(start -0.925 -0.47)
			(end 0.925 0.47)
			(stroke
				(width 0.05)
				(type default)
			)
			(fill no)
			(layer "F.CrtYd")
		)
		(fp_rect
			(start -0.5 -0.25)
			(end 0.5 0.25)
			(stroke
				(width 0.15)
				(type solid)
			)
			(fill no)
			(layer "F.Fab")
		)
		(fp_text user "License: Apache-2.0"
			(at -0.95 5.169 90)
			(layer "F.Fab")
			(effects
				(font
					(size 0.7 0.7)
					(thickness 0.15)
				)
				(justify left bottom)
			)
		)
		(fp_text user "${REFERENCE}"
			(at -0.95 3.168 90)
			(layer "F.Fab")
			(effects
				(font
					(size 0.7 0.7)
					(thickness 0.15)
				)
				(justify left bottom)
			)
		)
		(fp_text user "Author: Antmicro"
			(at -0.95 4.169 90)
			(layer "F.Fab")
			(effects
				(font
					(size 0.7 0.7)
					(thickness 0.15)
				)
				(justify left bottom)
			)
		)
		(pad "1" smd roundrect
			(at -0.48 0 90)
			(size 0.59 0.64)
			(layers "F.Cu" "F.Mask" "F.Paste")
			(roundrect_rratio 0.25)
			(net 437 "Net-(U15-A)")
			(pintype "passive")
		)
		(pad "2" smd roundrect
			(at 0.48 0 90)
			(size 0.59 0.64)
			(layers "F.Cu" "F.Mask" "F.Paste")
			(roundrect_rratio 0.25)
			(net 74 "/X710-AT2 Misc/LAN_PWR_GOOD")
			(pintype "passive")
		)
	)
)
